(kicad_pcb
	(version 20260206)
	(generator "pcbnew")
	(generator_version "10.0")
	(general
		(thickness 1.6)
		(legacy_teardrops no)
	)
	(paper "A4")
	(title_block
		(title "Bryce Canyon_IOM_M2_16342-2_OCP.brd")
		(comment 1 "Bryce Canyon / footprints 1043-1050 of 1146")
	)
	(layers
		(0 "F.Cu" signal "TOP")
		(4 "In1.Cu" signal "L2GND")
		(6 "In2.Cu" signal "L3")
		(8 "In3.Cu" signal "L4VCC")
		(10 "In4.Cu" signal "L5VCC")
		(12 "In5.Cu" signal "L6")
		(14 "In6.Cu" signal "L7GND")
		(2 "B.Cu" signal "BOTTOM")
		(9 "F.Adhes" user "F.Adhesive")
		(11 "B.Adhes" user "B.Adhesive")
		(13 "F.Paste" user "Package Geometry/Pastemask Top")
		(15 "B.Paste" user "Package Geometry/Pastemask Bottom")
		(5 "F.SilkS" user "Ref Des/Silkscreen Top")
		(7 "B.SilkS" user "Ref Des/Silkscreen Bottom")
		(1 "F.Mask" user "Board Geometry/Soldermask Top")
		(3 "B.Mask" user "Board Geometry/Soldermask Bottom")
		(17 "Dwgs.User" user "User.Drawings")
		(19 "Cmts.User" user "User.Comments")
		(21 "Eco1.User" user "User.Eco1")
		(23 "Eco2.User" user "User.Eco2")
		(25 "Edge.Cuts" user "Board Geometry/Outline")
		(27 "Margin" user)
		(31 "F.CrtYd" user "Package Geometry/Place Bound Top")
		(29 "B.CrtYd" user "Package Geometry/Place Bound Bottom")
		(35 "F.Fab" user "Ref Des/Assembly Top")
		(33 "B.Fab" user "Ref Des/Assembly Bottom")
	)
	(footprint ""
		(layer "B.Cu")
		(at 124.95784 -9.622282 90)
		(property "Reference" "R449"
			(at 0 0 90)
			(layer "B.SilkS")
			(hide yes)
			(effects
				(font
					(size 1.27 1.27)
				)
				(justify mirror)
			)
		)
		(property "Value" "1KR2J-1-GP"
			(at -0.064008 -3.993896 90)
			(unlocked yes)
			(layer "B.Fab")
			(hide yes)
			(effects
				(font
					(size 1.016 1.016)
					(thickness 0.1524)
				)
				(justify mirror)
			)
		)
		(property "Device Type" "R402H16"
			(at -0.064008 -5.517896 90)
			(unlocked yes)
			(layer "B.Fab")
			(hide yes)
			(effects
				(font
					(size 1.016 1.016)
					(thickness 0.1524)
				)
				(justify mirror)
			)
		)
		(duplicate_pad_numbers_are_jumpers no)
		(fp_line
			(start 0.508 -0.9398)
			(end 0.508 0.9398)
			(stroke
				(width 0.1524)
				(type default)
			)
			(layer "B.SilkS")
		)
		(fp_line
			(start -0.508 -0.9398)
			(end 0.508 -0.9398)
			(stroke
				(width 0.1524)
				(type default)
			)
			(layer "B.SilkS")
		)
		(fp_rect
			(start 0.508 0.9398)
			(end -0.508 -0.9398)
			(stroke
				(width 0)
				(type default)
			)
			(fill no)
			(layer "B.CrtYd")
		)
		(fp_rect
			(start 0.508 0.9398)
			(end -0.508 -0.9398)
			(stroke
				(width 0)
				(type default)
			)
			(fill no)
			(layer "B.Fab")
		)
		(pad "1" smd custom
			(at 0 -0.4445 270)
			(size 0.1397 0.1397)
			(layers "B.Cu" "B.Mask" "B.Paste")
			(net "MB0_CM_VOUT_R")
			(options
				(clearance outline)
				(anchor circle)
			)
			(primitives
				(gr_poly
					(pts
						(arc
							(start -0.1778 0.2794)
							(mid -0.249642 0.249642)
							(end -0.2794 0.1778)
						)
						(arc
							(start -0.2794 -0.1778)
							(mid -0.249642 -0.249642)
							(end -0.1778 -0.2794)
						)
						(arc
							(start 0.1778 -0.2794)
							(mid 0.249642 -0.249642)
							(end 0.2794 -0.1778)
						)
						(arc
							(start 0.2794 0.1778)
							(mid 0.249642 0.249642)
							(end 0.1778 0.2794)
						)
					)
					(width 0)
					(fill yes)
				)
			)
		)
		(pad "2" smd custom
			(at 0 0.4445 270)
			(size 0.1397 0.1397)
			(layers "B.Cu" "B.Mask" "B.Paste")
			(net "P12V_STBY")
			(options
				(clearance outline)
				(anchor circle)
			)
			(primitives
				(gr_poly
					(pts
						(arc
							(start -0.1778 0.2794)
							(mid -0.249642 0.249642)
							(end -0.2794 0.1778)
						)
						(arc
							(start -0.2794 -0.1778)
							(mid -0.249642 -0.249642)
							(end -0.1778 -0.2794)
						)
						(arc
							(start 0.1778 -0.2794)
							(mid 0.249642 -0.249642)
							(end 0.2794 -0.1778)
						)
						(arc
							(start 0.2794 0.1778)
							(mid 0.249642 0.249642)
							(end 0.1778 0.2794)
						)
					)
					(width 0)
					(fill yes)
				)
			)
		)
	)
	(footprint ""
		(layer "B.Cu")
		(at 57.3786 -154.9146)
		(property "Reference" "R303"
			(at 0 0 0)
			(layer "B.SilkS")
			(hide yes)
			(effects
				(font
					(size 1.27 1.27)
				)
				(justify mirror)
			)
		)
		(property "Value" "47KR2F-GP"
			(at -0.064008 -3.993896 0)
			(unlocked yes)
			(layer "B.Fab")
			(hide yes)
			(effects
				(font
					(size 1.016 1.016)
					(thickness 0.1524)
				)
				(justify mirror)
			)
		)
		(property "Device Type" "R402H16"
			(at -0.064008 -5.517896 0)
			(unlocked yes)
			(layer "B.Fab")
			(hide yes)
			(effects
				(font
					(size 1.016 1.016)
					(thickness 0.1524)
				)
				(justify mirror)
			)
		)
		(duplicate_pad_numbers_are_jumpers no)
		(fp_line
			(start -0.508 -0.9398)
			(end 0.508 -0.9398)
			(stroke
				(width 0.1524)
				(type default)
			)
			(layer "B.SilkS")
		)
		(fp_line
			(start 0.508 -0.9398)
			(end 0.508 0.9398)
			(stroke
				(width 0.1524)
				(type default)
			)
			(layer "B.SilkS")
		)
		(fp_rect
			(start 0.508 0.9398)
			(end -0.508 -0.9398)
			(stroke
				(width 0)
				(type default)
			)
			(fill no)
			(layer "B.CrtYd")
		)
		(fp_rect
			(start 0.508 0.9398)
			(end -0.508 -0.9398)
			(stroke
				(width 0)
				(type default)
			)
			(fill no)
			(layer "B.Fab")
		)
		(pad "1" smd custom
			(at 0 -0.4445 180)
			(size 0.1397 0.1397)
			(layers "B.Cu" "B.Mask" "B.Paste")
			(net "GND")
			(options
				(clearance outline)
				(anchor circle)
			)
			(primitives
				(gr_poly
					(pts
						(arc
							(start -0.1778 0.2794)
							(mid -0.249642 0.249642)
							(end -0.2794 0.1778)
						)
						(arc
							(start -0.2794 -0.1778)
							(mid -0.249642 -0.249642)
							(end -0.1778 -0.2794)
						)
						(arc
							(start 0.1778 -0.2794)
							(mid 0.249642 -0.249642)
							(end 0.2794 -0.1778)
						)
						(arc
							(start 0.2794 0.1778)
							(mid 0.249642 0.249642)
							(end 0.1778 0.2794)
						)
					)
					(width 0)
					(fill yes)
				)
			)
		)
		(pad "2" smd custom
			(at 0 0.4445 180)
			(size 0.1397 0.1397)
			(layers "B.Cu" "B.Mask" "B.Paste")
			(net "BMC_RGMII_C2_C3_D1_D2_E6")
			(options
				(clearance outline)
				(anchor circle)
			)
			(primitives
				(gr_poly
					(pts
						(arc
							(start -0.1778 0.2794)
							(mid -0.249642 0.249642)
							(end -0.2794 0.1778)
						)
						(arc
							(start -0.2794 -0.1778)
							(mid -0.249642 -0.249642)
							(end -0.1778 -0.2794)
						)
						(arc
							(start 0.1778 -0.2794)
							(mid 0.249642 -0.249642)
							(end 0.2794 -0.1778)
						)
						(arc
							(start 0.2794 0.1778)
							(mid 0.249642 0.249642)
							(end 0.1778 0.2794)
						)
					)
					(width 0)
					(fill yes)
				)
			)
		)
	)
	(footprint ""
		(layer "B.Cu")
		(at 55.72125 -147.754594)
		(property "Reference" "TP82"
			(at 0 0 0)
			(layer "B.SilkS")
			(hide yes)
			(effects
				(font
					(size 1.27 1.27)
				)
				(justify mirror)
			)
		)
		(property "Value" "TPAD28-2-GP"
			(at 0.0127 -1.6637 0)
			(unlocked yes)
			(layer "B.Fab")
			(hide yes)
			(effects
				(font
					(size 1.016 1.016)
					(thickness 0.1524)
				)
				(justify mirror)
			)
		)
		(property "Device Type" "TPAD28"
			(at 0.0127 -3.1877 0)
			(unlocked yes)
			(layer "B.Fab")
			(hide yes)
			(effects
				(font
					(size 1.016 1.016)
					(thickness 0.1524)
				)
				(justify mirror)
			)
		)
		(duplicate_pad_numbers_are_jumpers no)
		(fp_poly
			(pts
				(arc
					(start 0.3556 0)
					(mid -0.3556 0)
					(end 0.3556 0)
				)
			)
			(stroke
				(width 0)
				(type default)
			)
			(fill no)
			(layer "B.CrtYd")
		)
		(fp_poly
			(pts
				(arc
					(start 0.6096 0)
					(mid -0.6096 0)
					(end 0.6096 0)
				)
			)
			(stroke
				(width 0)
				(type default)
			)
			(fill no)
			(layer "B.Fab")
		)
		(pad "1" smd circle
			(at 0 0 180)
			(size 0.7112 0.7112)
			(layers "B.Cu" "B.Mask" "B.Paste")
			(net "BMC0_JTAG_RTCK")
		)
	)
	(footprint ""
		(layer "B.Cu")
		(at 62.73292 -142.308072)
		(property "Reference" "R195"
			(at 0 0 0)
			(layer "B.SilkS")
			(hide yes)
			(effects
				(font
					(size 1.27 1.27)
				)
				(justify mirror)
			)
		)
		(property "Value" "2K2R2F-GP"
			(at -0.064008 -3.993896 0)
			(unlocked yes)
			(layer "B.Fab")
			(hide yes)
			(effects
				(font
					(size 1.016 1.016)
					(thickness 0.1524)
				)
				(justify mirror)
			)
		)
		(property "Device Type" "R402H16"
			(at -0.064008 -5.517896 0)
			(unlocked yes)
			(layer "B.Fab")
			(hide yes)
			(effects
				(font
					(size 1.016 1.016)
					(thickness 0.1524)
				)
				(justify mirror)
			)
		)
		(duplicate_pad_numbers_are_jumpers no)
		(fp_line
			(start -0.508 -0.9398)
			(end 0.508 -0.9398)
			(stroke
				(width 0.1524)
				(type default)
			)
			(layer "B.SilkS")
		)
		(fp_line
			(start 0.508 -0.9398)
			(end 0.508 0.9398)
			(stroke
				(width 0.1524)
				(type default)
			)
			(layer "B.SilkS")
		)
		(fp_rect
			(start 0.508 0.9398)
			(end -0.508 -0.9398)
			(stroke
				(width 0)
				(type default)
			)
			(fill no)
			(layer "B.CrtYd")
		)
		(fp_rect
			(start 0.508 0.9398)
			(end -0.508 -0.9398)
			(stroke
				(width 0)
				(type default)
			)
			(fill no)
			(layer "B.Fab")
		)
		(pad "1" smd custom
			(at 0 -0.4445 180)
			(size 0.1397 0.1397)
			(layers "B.Cu" "B.Mask" "B.Paste")
			(net "I2C_EXP_LOC_SCL_OUT")
			(options
				(clearance outline)
				(anchor circle)
			)
			(primitives
				(gr_poly
					(pts
						(arc
							(start -0.1778 0.2794)
							(mid -0.249642 0.249642)
							(end -0.2794 0.1778)
						)
						(arc
							(start -0.2794 -0.1778)
							(mid -0.249642 -0.249642)
							(end -0.1778 -0.2794)
						)
						(arc
							(start 0.1778 -0.2794)
							(mid 0.249642 -0.249642)
							(end 0.2794 -0.1778)
						)
						(arc
							(start 0.2794 0.1778)
							(mid 0.249642 0.249642)
							(end 0.1778 0.2794)
						)
					)
					(width 0)
					(fill yes)
				)
			)
		)
		(pad "2" smd custom
			(at 0 0.4445 180)
			(size 0.1397 0.1397)
			(layers "B.Cu" "B.Mask" "B.Paste")
			(net "P3V3_STBY")
			(options
				(clearance outline)
				(anchor circle)
			)
			(primitives
				(gr_poly
					(pts
						(arc
							(start -0.1778 0.2794)
							(mid -0.249642 0.249642)
							(end -0.2794 0.1778)
						)
						(arc
							(start -0.2794 -0.1778)
							(mid -0.249642 -0.249642)
							(end -0.1778 -0.2794)
						)
						(arc
							(start 0.1778 -0.2794)
							(mid 0.249642 -0.249642)
							(end 0.2794 -0.1778)
						)
						(arc
							(start 0.2794 0.1778)
							(mid 0.249642 0.249642)
							(end 0.1778 0.2794)
						)
					)
					(width 0)
					(fill yes)
				)
			)
		)
	)
	(footprint ""
		(layer "B.Cu")
		(at 92.45092 -138.2268 -90)
		(property "Reference" "R275"
			(at 0 0 90)
			(layer "B.SilkS")
			(hide yes)
			(effects
				(font
					(size 1.27 1.27)
				)
				(justify mirror)
			)
		)
		(property "Value" "100KR2F-L1-GP"
			(at -0.064008 -3.993896 270)
			(unlocked yes)
			(layer "B.Fab")
			(hide yes)
			(effects
				(font
					(size 1.016 1.016)
					(thickness 0.1524)
				)
				(justify mirror)
			)
		)
		(property "Device Type" "R402H16"
			(at -0.064008 -5.517896 270)
			(unlocked yes)
			(layer "B.Fab")
			(hide yes)
			(effects
				(font
					(size 1.016 1.016)
					(thickness 0.1524)
				)
				(justify mirror)
			)
		)
		(duplicate_pad_numbers_are_jumpers no)
		(fp_line
			(start -0.508 -0.9398)
			(end 0.508 -0.9398)
			(stroke
				(width 0.1524)
				(type default)
			)
			(layer "B.SilkS")
		)
		(fp_line
			(start 0.508 -0.9398)
			(end 0.508 0.9398)
			(stroke
				(width 0.1524)
				(type default)
			)
			(layer "B.SilkS")
		)
		(fp_rect
			(start 0.508 0.9398)
			(end -0.508 -0.9398)
			(stroke
				(width 0)
				(type default)
			)
			(fill no)
			(layer "B.CrtYd")
		)
		(fp_rect
			(start 0.508 0.9398)
			(end -0.508 -0.9398)
			(stroke
				(width 0)
				(type default)
			)
			(fill no)
			(layer "B.Fab")
		)
		(pad "1" smd custom
			(at 0 -0.4445 90)
			(size 0.1397 0.1397)
			(layers "B.Cu" "B.Mask" "B.Paste")
			(net "DEBUG_CARD_PRSNT")
			(options
				(clearance outline)
				(anchor circle)
			)
			(primitives
				(gr_poly
					(pts
						(arc
							(start -0.1778 0.2794)
							(mid -0.249642 0.249642)
							(end -0.2794 0.1778)
						)
						(arc
							(start -0.2794 -0.1778)
							(mid -0.249642 -0.249642)
							(end -0.1778 -0.2794)
						)
						(arc
							(start 0.1778 -0.2794)
							(mid 0.249642 -0.249642)
							(end 0.2794 -0.1778)
						)
						(arc
							(start 0.2794 0.1778)
							(mid 0.249642 0.249642)
							(end 0.1778 0.2794)
						)
					)
					(width 0)
					(fill yes)
				)
			)
		)
		(pad "2" smd custom
			(at 0 0.4445 90)
			(size 0.1397 0.1397)
			(layers "B.Cu" "B.Mask" "B.Paste")
			(net "GND")
			(options
				(clearance outline)
				(anchor circle)
			)
			(primitives
				(gr_poly
					(pts
						(arc
							(start -0.1778 0.2794)
							(mid -0.249642 0.249642)
							(end -0.2794 0.1778)
						)
						(arc
							(start -0.2794 -0.1778)
							(mid -0.249642 -0.249642)
							(end -0.1778 -0.2794)
						)
						(arc
							(start 0.1778 -0.2794)
							(mid 0.249642 -0.249642)
							(end 0.2794 -0.1778)
						)
						(arc
							(start 0.2794 0.1778)
							(mid 0.249642 0.249642)
							(end 0.1778 0.2794)
						)
					)
					(width 0)
					(fill yes)
				)
			)
		)
	)
	(footprint ""
		(layer "B.Cu")
		(at 177.80635 -113.280444 90)
		(property "Reference" "C634"
			(at 0 0 90)
			(layer "B.SilkS")
			(hide yes)
			(effects
				(font
					(size 1.27 1.27)
				)
				(justify mirror)
			)
		)
		(property "Value" "SCD1U16V2KX-3GP"
			(at -1.1811 -2.7051 90)
			(unlocked yes)
			(layer "B.Fab")
			(hide yes)
			(effects
				(font
					(size 1.016 1.016)
					(thickness 0.1524)
				)
				(justify mirror)
			)
		)
		(property "Device Type" "C402H22"
			(at -1.1811 -4.2291 90)
			(unlocked yes)
			(layer "B.Fab")
			(hide yes)
			(effects
				(font
					(size 1.016 1.016)
					(thickness 0.1524)
				)
				(justify mirror)
			)
		)
		(duplicate_pad_numbers_are_jumpers no)
		(fp_rect
			(start 0.4318 0.9525)
			(end -0.4318 -0.9525)
			(stroke
				(width 0)
				(type default)
			)
			(fill no)
			(layer "B.CrtYd")
		)
		(fp_rect
			(start 0.4318 0.9525)
			(end -0.4318 -0.9525)
			(stroke
				(width 0)
				(type default)
			)
			(fill no)
			(layer "B.Fab")
		)
		(pad "1" smd custom
			(at 0 -0.4445 270)
			(size 0.1524 0.1524)
			(layers "B.Cu" "B.Mask" "B.Paste")
			(net "U83_VREF2")
			(options
				(clearance outline)
				(anchor circle)
			)
			(primitives
				(gr_poly
					(pts
						(arc
							(start 0.3048 0.2032)
							(mid 0.275042 0.275042)
							(end 0.2032 0.3048)
						)
						(arc
							(start -0.2032 0.3048)
							(mid -0.275042 0.275042)
							(end -0.3048 0.2032)
						)
						(arc
							(start -0.3048 -0.2032)
							(mid -0.275042 -0.275042)
							(end -0.2032 -0.3048)
						)
						(arc
							(start 0.2032 -0.3048)
							(mid 0.275042 -0.275042)
							(end 0.3048 -0.2032)
						)
					)
					(width 0)
					(fill yes)
				)
			)
		)
		(pad "2" smd custom
			(at 0 0.4445 270)
			(size 0.1524 0.1524)
			(layers "B.Cu" "B.Mask" "B.Paste")
			(net "GND")
			(options
				(clearance outline)
				(anchor circle)
			)
			(primitives
				(gr_poly
					(pts
						(arc
							(start 0.3048 0.2032)
							(mid 0.275042 0.275042)
							(end 0.2032 0.3048)
						)
						(arc
							(start -0.2032 0.3048)
							(mid -0.275042 0.275042)
							(end -0.3048 0.2032)
						)
						(arc
							(start -0.3048 -0.2032)
							(mid -0.275042 -0.275042)
							(end -0.2032 -0.3048)
						)
						(arc
							(start 0.2032 -0.3048)
							(mid 0.275042 -0.275042)
							(end 0.3048 -0.2032)
						)
					)
					(width 0)
					(fill yes)
				)
			)
		)
	)
	(footprint ""
		(layer "B.Cu")
		(at 59.962796 -136.357614 90)
		(property "Reference" "TP205"
			(at 0 0 90)
			(layer "B.SilkS")
			(hide yes)
			(effects
				(font
					(size 1.27 1.27)
				)
				(justify mirror)
			)
		)
		(property "Value" "TPAD28-2-GP"
			(at 0.0127 -1.6637 90)
			(unlocked yes)
			(layer "B.Fab")
			(hide yes)
			(effects
				(font
					(size 1.016 1.016)
					(thickness 0.1524)
				)
				(justify mirror)
			)
		)
		(property "Device Type" "TPAD28"
			(at 0.0127 -3.1877 90)
			(unlocked yes)
			(layer "B.Fab")
			(hide yes)
			(effects
				(font
					(size 1.016 1.016)
					(thickness 0.1524)
				)
				(justify mirror)
			)
		)
		(duplicate_pad_numbers_are_jumpers no)
		(fp_poly
			(pts
				(arc
					(start 0 0.3556)
					(mid 0 -0.3556)
					(end 0 0.3556)
				)
			)
			(stroke
				(width 0)
				(type default)
			)
			(fill no)
			(layer "B.CrtYd")
		)
		(fp_poly
			(pts
				(arc
					(start 0 0.6096)
					(mid 0 -0.6096)
					(end 0 0.6096)
				)
			)
			(stroke
				(width 0)
				(type default)
			)
			(fill no)
			(layer "B.Fab")
		)
		(pad "1" smd circle
			(at 0 0 270)
			(size 0.7112 0.7112)
			(layers "B.Cu" "B.Mask" "B.Paste")
			(net "TP_BMC_EXT1_LED_B")
		)
	)
	(footprint ""
		(layer "B.Cu")
		(at 64.262 -154.8892 -90)
		(property "Reference" "C80"
			(at 0 0 90)
			(layer "B.SilkS")
			(hide yes)
			(effects
				(font
					(size 1.27 1.27)
				)
				(justify mirror)
			)
		)
		(property "Value" "SCD1U16V2KX-3GP"
			(at -1.1811 -2.7051 270)
			(unlocked yes)
			(layer "B.Fab")
			(hide yes)
			(effects
				(font
					(size 1.016 1.016)
					(thickness 0.1524)
				)
				(justify mirror)
			)
		)
		(property "Device Type" "C402H22"
			(at -1.1811 -4.2291 270)
			(unlocked yes)
			(layer "B.Fab")
			(hide yes)
			(effects
				(font
					(size 1.016 1.016)
					(thickness 0.1524)
				)
				(justify mirror)
			)
		)
		(duplicate_pad_numbers_are_jumpers no)
		(fp_rect
			(start 0.4318 0.9525)
			(end -0.4318 -0.9525)
			(stroke
				(width 0)
				(type default)
			)
			(fill no)
			(layer "B.CrtYd")
		)
		(fp_rect
			(start 0.4318 0.9525)
			(end -0.4318 -0.9525)
			(stroke
				(width 0)
				(type default)
			)
			(fill no)
			(layer "B.Fab")
		)
		(pad "1" smd custom
			(at 0 -0.4445 90)
			(size 0.1524 0.1524)
			(layers "B.Cu" "B.Mask" "B.Paste")
			(net "P3V3_STBY")
			(options
				(clearance outline)
				(anchor circle)
			)
			(primitives
				(gr_poly
					(pts
						(arc
							(start 0.3048 0.2032)
							(mid 0.275042 0.275042)
							(end 0.2032 0.3048)
						)
						(arc
							(start -0.2032 0.3048)
							(mid -0.275042 0.275042)
							(end -0.3048 0.2032)
						)
						(arc
							(start -0.3048 -0.2032)
							(mid -0.275042 -0.275042)
							(end -0.2032 -0.3048)
						)
						(arc
							(start 0.2032 -0.3048)
							(mid 0.275042 -0.275042)
							(end 0.3048 -0.2032)
						)
					)
					(width 0)
					(fill yes)
				)
			)
		)
		(pad "2" smd custom
			(at 0 0.4445 90)
			(size 0.1524 0.1524)
			(layers "B.Cu" "B.Mask" "B.Paste")
			(net "GND")
			(options
				(clearance outline)
				(anchor circle)
			)
			(primitives
				(gr_poly
					(pts
						(arc
							(start 0.3048 0.2032)
							(mid 0.275042 0.275042)
							(end 0.2032 0.3048)
						)
						(arc
							(start -0.2032 0.3048)
							(mid -0.275042 0.275042)
							(end -0.3048 0.2032)
						)
						(arc
							(start -0.3048 -0.2032)
							(mid -0.275042 -0.275042)
							(end -0.2032 -0.3048)
						)
						(arc
							(start 0.2032 -0.3048)
							(mid 0.275042 -0.275042)
							(end 0.3048 -0.2032)
						)
					)
					(width 0)
					(fill yes)
				)
			)
		)
	)
)
